(kicad_pcb
	(version 20260206)
	(generator "pcbnew")
	(generator_version "10.0")
	(general
		(thickness 1.6)
		(legacy_teardrops no)
	)
	(paper "A4")
	(title_block
		(title "04192023_DAF0TMB3IC0_F0TG_MB_C_brd_V02_OCP.brd")
		(comment 1 "Grand Teton / footprints 7308-7313 of 8354")
	)
	(layers
		(0 "F.Cu" signal "TOP")
		(4 "In1.Cu" signal "GND")
		(6 "In2.Cu" signal "IN1")
		(8 "In3.Cu" signal "GND1")
		(10 "In4.Cu" signal "IN2")
		(12 "In5.Cu" signal "GND2")
		(14 "In6.Cu" signal "IN3")
		(16 "In7.Cu" signal "GND3")
		(18 "In8.Cu" signal "VCC")
		(20 "In9.Cu" signal "VCC1")
		(22 "In10.Cu" signal "GND4")
		(24 "In11.Cu" signal "IN4")
		(26 "In12.Cu" signal "GND5")
		(28 "In13.Cu" signal "IN5")
		(30 "In14.Cu" signal "GND6")
		(32 "In15.Cu" signal "IN6")
		(34 "In16.Cu" signal "GND7")
		(2 "B.Cu" signal "BOTTOM")
		(9 "F.Adhes" user "F.Adhesive")
		(11 "B.Adhes" user "B.Adhesive")
		(13 "F.Paste" user "Package Geometry/Pastemask Top")
		(15 "B.Paste" user "Package Geometry/Pastemask Bottom")
		(5 "F.SilkS" user "Ref Des/Silkscreen Top")
		(7 "B.SilkS" user "Ref Des/Silkscreen Bottom")
		(1 "F.Mask" user "Board Geometry/Soldermask Top")
		(3 "B.Mask" user "Board Geometry/Soldermask Bottom")
		(17 "Dwgs.User" user "User.Drawings")
		(19 "Cmts.User" user "User.Comments")
		(21 "Eco1.User" user "User.Eco1")
		(23 "Eco2.User" user "User.Eco2")
		(25 "Edge.Cuts" user "Board Geometry/Outline")
		(27 "Margin" user)
		(31 "F.CrtYd" user "Package Geometry/Place Bound Top")
		(29 "B.CrtYd" user "Package Geometry/Place Bound Bottom")
		(35 "F.Fab" user "Ref Des/Assembly Top")
		(33 "B.Fab" user "Ref Des/Assembly Bottom")
	)
	(footprint ""
		(layer "B.Cu")
		(at 129.067814 -381.11303)
		(property "Reference" "C7030"
			(at 2.21742 3.131312 0)
			(unlocked yes)
			(layer "B.SilkS")
			(effects
				(font
					(size 0.7874 0.5842)
					(thickness 0.1524)
				)
				(justify left mirror)
			)
		)
		(property "Value" ""
			(at 0 0 0)
			(layer "B.Fab")
			(effects
				(font
					(size 1.27 1.27)
				)
				(justify mirror)
			)
		)
		(duplicate_pad_numbers_are_jumpers no)
		(fp_line
			(start -4.53898 -2.15011)
			(end -4.53898 2.15011)
			(stroke
				(width 0.1524)
				(type default)
			)
			(layer "B.SilkS")
		)
		(fp_line
			(start -4.53898 2.15011)
			(end 4.53898 2.15011)
			(stroke
				(width 0.1524)
				(type default)
			)
			(layer "B.SilkS")
		)
		(fp_line
			(start 4.53898 -2.150618)
			(end 4.539742 2.152142)
			(stroke
				(width 0.1524)
				(type default)
			)
			(layer "B.SilkS")
		)
		(fp_line
			(start 4.53898 -2.15011)
			(end -4.53898 -2.15011)
			(stroke
				(width 0.1524)
				(type default)
			)
			(layer "B.SilkS")
		)
		(fp_line
			(start 4.53898 2.15011)
			(end 4.53898 -2.15011)
			(stroke
				(width 0.1524)
				(type default)
			)
			(layer "B.SilkS")
		)
		(fp_line
			(start 4.69138 -2.150618)
			(end 4.692396 2.161032)
			(stroke
				(width 0.1524)
				(type default)
			)
			(layer "B.SilkS")
		)
		(fp_line
			(start 4.83108 2.150364)
			(end 4.447794 2.149348)
			(stroke
				(width 0.1524)
				(type default)
			)
			(layer "B.SilkS")
		)
		(fp_line
			(start 4.84378 -2.150618)
			(end 4.53898 -2.150618)
			(stroke
				(width 0.1524)
				(type default)
			)
			(layer "B.SilkS")
		)
		(fp_line
			(start 4.84378 -2.150618)
			(end 4.842256 2.163064)
			(stroke
				(width 0.1524)
				(type default)
			)
			(layer "B.SilkS")
		)
		(fp_line
			(start -3.64998 -2.15011)
			(end -3.64998 2.15011)
			(stroke
				(width 0.1)
				(type default)
			)
			(layer "B.Fab")
		)
		(fp_line
			(start -3.64998 2.15011)
			(end 3.64998 2.15011)
			(stroke
				(width 0.1)
				(type default)
			)
			(layer "B.Fab")
		)
		(fp_line
			(start 3.64998 -2.15011)
			(end -3.64998 -2.15011)
			(stroke
				(width 0.1)
				(type default)
			)
			(layer "B.Fab")
		)
		(fp_line
			(start 3.64998 2.15011)
			(end 3.64998 -2.15011)
			(stroke
				(width 0.1)
				(type default)
			)
			(layer "B.Fab")
		)
		(fp_text user "-"
			(at -2.804414 2.313432 0)
			(unlocked yes)
			(layer "B.SilkS")
			(effects
				(font
					(size 1.905 1.4224)
					(thickness 0.1524)
				)
				(justify left mirror)
			)
		)
		(fp_text user "+"
			(at 6.214872 -0.337058 0)
			(unlocked yes)
			(layer "B.SilkS")
			(effects
				(font
					(size 1.905 1.4224)
					(thickness 0.1524)
				)
				(justify left mirror)
			)
		)
		(fp_text user "-"
			(at -4.313174 -0.094488 0)
			(unlocked yes)
			(layer "B.Fab")
			(effects
				(font
					(size 1.905 1.4224)
					(thickness 0.1524)
				)
				(justify left mirror)
			)
		)
		(fp_text user "+"
			(at 6.214872 -0.337058 0)
			(unlocked yes)
			(layer "B.Fab")
			(effects
				(font
					(size 1.905 1.4224)
					(thickness 0.1524)
				)
				(justify left mirror)
			)
		)
		(pad "1" smd rect
			(at 3.199892 0 180)
			(size 2.413 2.8194)
			(layers "B.Cu" "B.Mask" "B.Paste")
			(net "P0V9_CPU1_RT3_2A")
		)
		(pad "2" smd rect
			(at -3.199892 0 180)
			(size 2.413 2.8194)
			(layers "B.Cu" "B.Mask" "B.Paste")
			(net "GND")
		)
	)
	(footprint ""
		(layer "B.Cu")
		(at 301.418244 -395.43228)
		(property "Reference" "C555"
			(at 0 0 0)
			(layer "B.SilkS")
			(hide yes)
			(effects
				(font
					(size 1.27 1.27)
				)
				(justify mirror)
			)
		)
		(property "Value" ""
			(at 0 0 0)
			(layer "B.Fab")
			(effects
				(font
					(size 1.27 1.27)
				)
				(justify mirror)
			)
		)
		(duplicate_pad_numbers_are_jumpers no)
		(fp_line
			(start -0.299974 -0.150114)
			(end -0.299974 0.150114)
			(stroke
				(width 0.1)
				(type default)
			)
			(layer "B.Fab")
		)
		(fp_line
			(start -0.299974 0.150114)
			(end 0.299974 0.150114)
			(stroke
				(width 0.1)
				(type default)
			)
			(layer "B.Fab")
		)
		(fp_line
			(start 0.299974 -0.150114)
			(end -0.299974 -0.150114)
			(stroke
				(width 0.1)
				(type default)
			)
			(layer "B.Fab")
		)
		(fp_line
			(start 0.299974 0.150114)
			(end 0.299974 -0.150114)
			(stroke
				(width 0.1)
				(type default)
			)
			(layer "B.Fab")
		)
		(pad "1" smd rect
			(at 0.2667 0 180)
			(size 0.3048 0.381)
			(layers "B.Cu" "B.Mask" "B.Paste")
			(net "P0V9_CPU0_RT0_2A")
		)
		(pad "2" smd rect
			(at -0.2667 0 180)
			(size 0.3048 0.381)
			(layers "B.Cu" "B.Mask" "B.Paste")
			(net "GND")
		)
	)
	(footprint ""
		(layer "B.Cu")
		(at 63.55588 -8.981948 90)
		(property "Reference" "C1838"
			(at 0 0 90)
			(layer "B.SilkS")
			(hide yes)
			(effects
				(font
					(size 1.27 1.27)
				)
				(justify mirror)
			)
		)
		(property "Value" ""
			(at 0 0 90)
			(layer "B.Fab")
			(effects
				(font
					(size 1.27 1.27)
				)
				(justify mirror)
			)
		)
		(duplicate_pad_numbers_are_jumpers no)
		(fp_line
			(start 0.7874 -0.4064)
			(end -0.7874 -0.4064)
			(stroke
				(width 0.1524)
				(type default)
			)
			(layer "B.SilkS")
		)
		(fp_line
			(start -0.7874 -0.4064)
			(end -0.7874 0.4064)
			(stroke
				(width 0.1524)
				(type default)
			)
			(layer "B.SilkS")
		)
		(fp_line
			(start 0.7874 0.4064)
			(end 0.7874 -0.4064)
			(stroke
				(width 0.1524)
				(type default)
			)
			(layer "B.SilkS")
		)
		(fp_line
			(start -0.7874 0.4064)
			(end 0.7874 0.4064)
			(stroke
				(width 0.1524)
				(type default)
			)
			(layer "B.SilkS")
		)
		(fp_line
			(start 0.67945 -0.305054)
			(end 0.12065 -0.305054)
			(stroke
				(width 0.1)
				(type default)
			)
			(layer "B.Fab")
		)
		(fp_line
			(start 0.12065 -0.305054)
			(end 0.12065 -0.2794)
			(stroke
				(width 0.1)
				(type default)
			)
			(layer "B.Fab")
		)
		(fp_line
			(start -0.12065 -0.3048)
			(end -0.67945 -0.3048)
			(stroke
				(width 0.1)
				(type default)
			)
			(layer "B.Fab")
		)
		(fp_line
			(start -0.67945 -0.3048)
			(end -0.67945 0.3048)
			(stroke
				(width 0.1)
				(type default)
			)
			(layer "B.Fab")
		)
		(fp_line
			(start 0.12065 -0.2794)
			(end -0.12065 -0.2794)
			(stroke
				(width 0.1)
				(type default)
			)
			(layer "B.Fab")
		)
		(fp_line
			(start -0.12065 -0.2794)
			(end -0.12065 -0.3048)
			(stroke
				(width 0.1)
				(type default)
			)
			(layer "B.Fab")
		)
		(fp_line
			(start 0.12065 0.2794)
			(end 0.12065 0.3048)
			(stroke
				(width 0.1)
				(type default)
			)
			(layer "B.Fab")
		)
		(fp_line
			(start -0.120396 0.2794)
			(end 0.12065 0.2794)
			(stroke
				(width 0.1)
				(type default)
			)
			(layer "B.Fab")
		)
		(fp_line
			(start 0.67945 0.3048)
			(end 0.67945 -0.305054)
			(stroke
				(width 0.1)
				(type default)
			)
			(layer "B.Fab")
		)
		(fp_line
			(start 0.12065 0.3048)
			(end 0.67945 0.3048)
			(stroke
				(width 0.1)
				(type default)
			)
			(layer "B.Fab")
		)
		(fp_line
			(start -0.120396 0.3048)
			(end -0.120396 0.2794)
			(stroke
				(width 0.1)
				(type default)
			)
			(layer "B.Fab")
		)
		(fp_line
			(start -0.67945 0.3048)
			(end -0.120396 0.3048)
			(stroke
				(width 0.1)
				(type default)
			)
			(layer "B.Fab")
		)
		(pad "1" smd circle
			(at 0.40005 0 270)
			(size 0 0)
			(layers "B.Cu" "B.Mask" "B.Paste")
			(net "P3V3_OCP_V3_2")
		)
		(pad "2" smd circle
			(at -0.40005 0 270)
			(size 0 0)
			(layers "B.Cu" "B.Mask" "B.Paste")
			(net "GND")
		)
	)
	(footprint ""
		(layer "B.Cu")
		(at 415.712402 -193.99631)
		(property "Reference" "C116"
			(at 0 0 0)
			(layer "B.SilkS")
			(hide yes)
			(effects
				(font
					(size 1.27 1.27)
				)
				(justify mirror)
			)
		)
		(property "Value" ""
			(at 0 0 0)
			(layer "B.Fab")
			(effects
				(font
					(size 1.27 1.27)
				)
				(justify mirror)
			)
		)
		(duplicate_pad_numbers_are_jumpers no)
		(fp_line
			(start -0.7874 -0.4064)
			(end -0.7874 0.4064)
			(stroke
				(width 0.1524)
				(type default)
			)
			(layer "B.SilkS")
		)
		(fp_line
			(start -0.7874 0.4064)
			(end 0.7874 0.4064)
			(stroke
				(width 0.1524)
				(type default)
			)
			(layer "B.SilkS")
		)
		(fp_line
			(start 0.7874 -0.4064)
			(end -0.7874 -0.4064)
			(stroke
				(width 0.1524)
				(type default)
			)
			(layer "B.SilkS")
		)
		(fp_line
			(start 0.7874 0.4064)
			(end 0.7874 -0.4064)
			(stroke
				(width 0.1524)
				(type default)
			)
			(layer "B.SilkS")
		)
		(fp_line
			(start -0.67945 -0.3048)
			(end -0.67945 0.3048)
			(stroke
				(width 0.1)
				(type default)
			)
			(layer "B.Fab")
		)
		(fp_line
			(start -0.67945 0.3048)
			(end -0.120396 0.3048)
			(stroke
				(width 0.1)
				(type default)
			)
			(layer "B.Fab")
		)
		(fp_line
			(start -0.12065 -0.3048)
			(end -0.67945 -0.3048)
			(stroke
				(width 0.1)
				(type default)
			)
			(layer "B.Fab")
		)
		(fp_line
			(start -0.12065 -0.2794)
			(end -0.12065 -0.3048)
			(stroke
				(width 0.1)
				(type default)
			)
			(layer "B.Fab")
		)
		(fp_line
			(start -0.120396 0.2794)
			(end 0.12065 0.2794)
			(stroke
				(width 0.1)
				(type default)
			)
			(layer "B.Fab")
		)
		(fp_line
			(start -0.120396 0.3048)
			(end -0.120396 0.2794)
			(stroke
				(width 0.1)
				(type default)
			)
			(layer "B.Fab")
		)
		(fp_line
			(start 0.12065 -0.305054)
			(end 0.12065 -0.2794)
			(stroke
				(width 0.1)
				(type default)
			)
			(layer "B.Fab")
		)
		(fp_line
			(start 0.12065 -0.2794)
			(end -0.12065 -0.2794)
			(stroke
				(width 0.1)
				(type default)
			)
			(layer "B.Fab")
		)
		(fp_line
			(start 0.12065 0.2794)
			(end 0.12065 0.3048)
			(stroke
				(width 0.1)
				(type default)
			)
			(layer "B.Fab")
		)
		(fp_line
			(start 0.12065 0.3048)
			(end 0.67945 0.3048)
			(stroke
				(width 0.1)
				(type default)
			)
			(layer "B.Fab")
		)
		(fp_line
			(start 0.67945 -0.305054)
			(end 0.12065 -0.305054)
			(stroke
				(width 0.1)
				(type default)
			)
			(layer "B.Fab")
		)
		(fp_line
			(start 0.67945 0.3048)
			(end 0.67945 -0.305054)
			(stroke
				(width 0.1)
				(type default)
			)
			(layer "B.Fab")
		)
		(pad "1" smd circle
			(at 0.40005 0 180)
			(size 0 0)
			(layers "B.Cu" "B.Mask" "B.Paste")
			(net "P3V3_AUX")
		)
		(pad "2" smd circle
			(at -0.40005 0 180)
			(size 0 0)
			(layers "B.Cu" "B.Mask" "B.Paste")
			(net "GND")
		)
	)
	(footprint ""
		(layer "B.Cu")
		(at 126.375668 -35.203892)
		(property "Reference" "C6055"
			(at 0 0 0)
			(layer "B.SilkS")
			(hide yes)
			(effects
				(font
					(size 1.27 1.27)
				)
				(justify mirror)
			)
		)
		(property "Value" ""
			(at 0 0 0)
			(layer "B.Fab")
			(effects
				(font
					(size 1.27 1.27)
				)
				(justify mirror)
			)
		)
		(duplicate_pad_numbers_are_jumpers no)
		(fp_line
			(start -0.7874 -0.4064)
			(end -0.7874 0.4064)
			(stroke
				(width 0.1524)
				(type default)
			)
			(layer "B.SilkS")
		)
		(fp_line
			(start -0.7874 0.4064)
			(end 0.7874 0.4064)
			(stroke
				(width 0.1524)
				(type default)
			)
			(layer "B.SilkS")
		)
		(fp_line
			(start 0.7874 -0.4064)
			(end -0.7874 -0.4064)
			(stroke
				(width 0.1524)
				(type default)
			)
			(layer "B.SilkS")
		)
		(fp_line
			(start 0.7874 0.4064)
			(end 0.7874 -0.4064)
			(stroke
				(width 0.1524)
				(type default)
			)
			(layer "B.SilkS")
		)
		(fp_line
			(start -0.67945 -0.3048)
			(end -0.67945 0.3048)
			(stroke
				(width 0.1)
				(type default)
			)
			(layer "B.Fab")
		)
		(fp_line
			(start -0.67945 0.3048)
			(end -0.120396 0.3048)
			(stroke
				(width 0.1)
				(type default)
			)
			(layer "B.Fab")
		)
		(fp_line
			(start -0.12065 -0.3048)
			(end -0.67945 -0.3048)
			(stroke
				(width 0.1)
				(type default)
			)
			(layer "B.Fab")
		)
		(fp_line
			(start -0.12065 -0.2794)
			(end -0.12065 -0.3048)
			(stroke
				(width 0.1)
				(type default)
			)
			(layer "B.Fab")
		)
		(fp_line
			(start -0.120396 0.2794)
			(end 0.12065 0.2794)
			(stroke
				(width 0.1)
				(type default)
			)
			(layer "B.Fab")
		)
		(fp_line
			(start -0.120396 0.3048)
			(end -0.120396 0.2794)
			(stroke
				(width 0.1)
				(type default)
			)
			(layer "B.Fab")
		)
		(fp_line
			(start 0.12065 -0.305054)
			(end 0.12065 -0.2794)
			(stroke
				(width 0.1)
				(type default)
			)
			(layer "B.Fab")
		)
		(fp_line
			(start 0.12065 -0.2794)
			(end -0.12065 -0.2794)
			(stroke
				(width 0.1)
				(type default)
			)
			(layer "B.Fab")
		)
		(fp_line
			(start 0.12065 0.2794)
			(end 0.12065 0.3048)
			(stroke
				(width 0.1)
				(type default)
			)
			(layer "B.Fab")
		)
		(fp_line
			(start 0.12065 0.3048)
			(end 0.67945 0.3048)
			(stroke
				(width 0.1)
				(type default)
			)
			(layer "B.Fab")
		)
		(fp_line
			(start 0.67945 -0.305054)
			(end 0.12065 -0.305054)
			(stroke
				(width 0.1)
				(type default)
			)
			(layer "B.Fab")
		)
		(fp_line
			(start 0.67945 0.3048)
			(end 0.67945 -0.305054)
			(stroke
				(width 0.1)
				(type default)
			)
			(layer "B.Fab")
		)
		(pad "1" smd circle
			(at 0.40005 0 180)
			(size 0 0)
			(layers "B.Cu" "B.Mask" "B.Paste")
			(net "P1V2_AUX")
		)
		(pad "2" smd circle
			(at -0.40005 0 180)
			(size 0 0)
			(layers "B.Cu" "B.Mask" "B.Paste")
			(net "GND")
		)
	)
	(footprint ""
		(layer "B.Cu")
		(at 112.427004 -261.748016 90)
		(property "Reference" "C2510"
			(at 0 0 90)
			(layer "B.SilkS")
			(hide yes)
			(effects
				(font
					(size 1.27 1.27)
				)
				(justify mirror)
			)
		)
		(property "Value" ""
			(at 0 0 90)
			(layer "B.Fab")
			(effects
				(font
					(size 1.27 1.27)
				)
				(justify mirror)
			)
		)
		(duplicate_pad_numbers_are_jumpers no)
		(fp_line
			(start 0.7874 -0.4064)
			(end -0.7874 -0.4064)
			(stroke
				(width 0.1524)
				(type default)
			)
			(layer "B.SilkS")
		)
		(fp_line
			(start -0.7874 -0.4064)
			(end -0.7874 0.4064)
			(stroke
				(width 0.1524)
				(type default)
			)
			(layer "B.SilkS")
		)
		(fp_line
			(start 0.7874 0.4064)
			(end 0.7874 -0.4064)
			(stroke
				(width 0.1524)
				(type default)
			)
			(layer "B.SilkS")
		)
		(fp_line
			(start -0.7874 0.4064)
			(end 0.7874 0.4064)
			(stroke
				(width 0.1524)
				(type default)
			)
			(layer "B.SilkS")
		)
		(fp_line
			(start 0.67945 -0.305054)
			(end 0.12065 -0.305054)
			(stroke
				(width 0.1)
				(type default)
			)
			(layer "B.Fab")
		)
		(fp_line
			(start 0.12065 -0.305054)
			(end 0.12065 -0.2794)
			(stroke
				(width 0.1)
				(type default)
			)
			(layer "B.Fab")
		)
		(fp_line
			(start -0.12065 -0.3048)
			(end -0.67945 -0.3048)
			(stroke
				(width 0.1)
				(type default)
			)
			(layer "B.Fab")
		)
		(fp_line
			(start -0.67945 -0.3048)
			(end -0.67945 0.3048)
			(stroke
				(width 0.1)
				(type default)
			)
			(layer "B.Fab")
		)
		(fp_line
			(start 0.12065 -0.2794)
			(end -0.12065 -0.2794)
			(stroke
				(width 0.1)
				(type default)
			)
			(layer "B.Fab")
		)
		(fp_line
			(start -0.12065 -0.2794)
			(end -0.12065 -0.3048)
			(stroke
				(width 0.1)
				(type default)
			)
			(layer "B.Fab")
		)
		(fp_line
			(start 0.12065 0.2794)
			(end 0.12065 0.3048)
			(stroke
				(width 0.1)
				(type default)
			)
			(layer "B.Fab")
		)
		(fp_line
			(start -0.120396 0.2794)
			(end 0.12065 0.2794)
			(stroke
				(width 0.1)
				(type default)
			)
			(layer "B.Fab")
		)
		(fp_line
			(start 0.67945 0.3048)
			(end 0.67945 -0.305054)
			(stroke
				(width 0.1)
				(type default)
			)
			(layer "B.Fab")
		)
		(fp_line
			(start 0.12065 0.3048)
			(end 0.67945 0.3048)
			(stroke
				(width 0.1)
				(type default)
			)
			(layer "B.Fab")
		)
		(fp_line
			(start -0.120396 0.3048)
			(end -0.120396 0.2794)
			(stroke
				(width 0.1)
				(type default)
			)
			(layer "B.Fab")
		)
		(fp_line
			(start -0.67945 0.3048)
			(end -0.120396 0.3048)
			(stroke
				(width 0.1)
				(type default)
			)
			(layer "B.Fab")
		)
		(pad "1" smd circle
			(at 0.40005 0 270)
			(size 0 0)
			(layers "B.Cu" "B.Mask" "B.Paste")
			(net "PVDD11_S3_P1")
		)
		(pad "2" smd circle
			(at -0.40005 0 270)
			(size 0 0)
			(layers "B.Cu" "B.Mask" "B.Paste")
			(net "GND")
		)
	)
)
